G04 ================== begin FILE IDENTIFICATION RECORD ==================*
G04 Layout Name:  15750-1.brd*
G04 Film Name:    L4GND*
G04 File Format:  Gerber RS274X*
G04 File Origin:  Cadence Allegro 16.5-S056*
G04 Origin Date:  Fri Dec 30 13:21:37 2016*
G04 *
G04 Layer:  VIA CLASS/L4GND*
G04 Layer:  PIN/L4GND*
G04 Layer:  ETCH/L4GND*
G04 Layer:  DRAWING FORMAT/LAYER_L4GND*
G04 Layer:  DRAWING FORMAT/LAYER_PCB_STORY*
G04 *
G04 Offset:    (0.00 0.00)*
G04 Mirror:    No*
G04 Mode:      Negative*
G04 Rotation:  0*
G04 FullContactRelief:  No*
G04 UndefLineWidth:     6.00*
G04 ================== end FILE IDENTIFICATION RECORD ====================*
%FSLAX35Y35*MOIN*%
%IR0*IPPOS*OFA0.00000B0.00000*MIA0B0*SFA1.00000B1.00000*%
%ADD15C,.03*%
%ADD14C,.032*%
%ADD17C,.072*%
%ADD16C,.091*%
%ADD20C,.093*%
%ADD18C,.068*%
%AMMACRO12*
4,1,15,.00398,.00044,
.003999,.000208,
.004004,-.000025,
.003996,-.000258,
.00398,-.00044,
.00483,-.00129,
.004897,-.001007,
.004947,-.000721,
.004981,-.000432,
.004997,-.000141,
.004997,.000149,
.00498,.00044,
.004946,.000729,
.004895,.001015,
.00483,.00129,
.00398,.00044,
0.0*
4,1,15,.00044,-.00398,
.000208,-.003999,
-.000025,-.004004,
-.000258,-.003996,
-.00044,-.00398,
-.00129,-.00483,
-.001007,-.004897,
-.000721,-.004947,
-.000432,-.004981,
-.000141,-.004997,
.000149,-.004997,
.00044,-.00498,
.000729,-.004946,
.001015,-.004895,
.00129,-.00483,
.00044,-.00398,
0.0*
4,1,15,-.00398,-.00044,
-.003999,-.000208,
-.004004,.000025,
-.003996,.000258,
-.00398,.00044,
-.00483,.00129,
-.004897,.001007,
-.004947,.000721,
-.004981,.000432,
-.004997,.000141,
-.004997,-.000149,
-.00498,-.00044,
-.004946,-.000729,
-.004895,-.001015,
-.00483,-.00129,
-.00398,-.00044,
0.0*
4,1,15,-.00044,.00398,
-.000208,.003999,
.000025,.004004,
.000258,.003996,
.00044,.00398,
.00129,.00483,
.001007,.004897,
.000721,.004947,
.000432,.004981,
.000141,.004997,
-.000149,.004997,
-.00044,.00498,
-.000729,.004946,
-.001015,.004895,
-.00129,.00483,
-.00044,.00398,
0.0*
%
%ADD12MACRO12*%
%AMMACRO19*
4,1,13,.02632,.01218,
.028035,.007425,
.028899,.002443,
.028884,-.002612,
.027991,-.007588,
.02632,-.01218,
.03005,-.01591,
.032356,-.01045,
.033679,-.004673,
.033979,.001247,
.033246,.007128,
.031504,.012793,
.03005,.01591,
.02632,.01218,
270.*
4,1,13,.01218,-.02632,
.007425,-.028035,
.002443,-.028899,
-.002612,-.028884,
-.007588,-.027991,
-.01218,-.02632,
-.01591,-.03005,
-.01045,-.032356,
-.004673,-.033679,
.001247,-.033979,
.007128,-.033246,
.012793,-.031504,
.01591,-.03005,
.01218,-.02632,
270.*
4,1,13,-.02632,-.01218,
-.028035,-.007425,
-.028899,-.002443,
-.028884,.002612,
-.027991,.007588,
-.02632,.01218,
-.03005,.01591,
-.032356,.01045,
-.033679,.004673,
-.033979,-.001247,
-.033246,-.007128,
-.031504,-.012793,
-.03005,-.01591,
-.02632,-.01218,
270.*
4,1,13,-.01218,.02632,
-.007425,.028035,
-.002443,.028899,
.002612,.028884,
.007588,.027991,
.01218,.02632,
.01591,.03005,
.01045,.032356,
.004673,.033679,
-.001247,.033979,
-.007128,.033246,
-.012793,.031504,
-.01591,.03005,
-.01218,.02632,
270.*
%
%ADD19MACRO19*%
%ADD10C,.114*%
%AMMACRO13*
4,1,15,.00398,.00044,
.003999,.000208,
.004004,-.000025,
.003996,-.000258,
.00398,-.00044,
.00483,-.00129,
.004897,-.001007,
.004947,-.000721,
.004981,-.000432,
.004997,-.000141,
.004997,.000149,
.00498,.00044,
.004946,.000729,
.004895,.001015,
.00483,.00129,
.00398,.00044,
270.*
4,1,15,.00044,-.00398,
.000208,-.003999,
-.000025,-.004004,
-.000258,-.003996,
-.00044,-.00398,
-.00129,-.00483,
-.001007,-.004897,
-.000721,-.004947,
-.000432,-.004981,
-.000141,-.004997,
.000149,-.004997,
.00044,-.00498,
.000729,-.004946,
.001015,-.004895,
.00129,-.00483,
.00044,-.00398,
270.*
4,1,15,-.00398,-.00044,
-.003999,-.000208,
-.004004,.000025,
-.003996,.000258,
-.00398,.00044,
-.00483,.00129,
-.004897,.001007,
-.004947,.000721,
-.004981,.000432,
-.004997,.000141,
-.004997,-.000149,
-.00498,-.00044,
-.004946,-.000729,
-.004895,-.001015,
-.00483,-.00129,
-.00398,-.00044,
270.*
4,1,15,-.00044,.00398,
-.000208,.003999,
.000025,.004004,
.000258,.003996,
.00044,.00398,
.00129,.00483,
.001007,.004897,
.000721,.004947,
.000432,.004981,
.000141,.004997,
-.000149,.004997,
-.00044,.00498,
-.000729,.004946,
-.001015,.004895,
-.00129,.00483,
-.00044,.00398,
270.*
%
%ADD13MACRO13*%
%AMMACRO11*
4,1,16,.07256,.04427,
.079145,.030998,
.083325,.016783,
.084974,.002059,
.08404,-.012728,
.080553,-.027128,
.074619,-.040704,
.07256,-.04427,
.07619,-.04791,
.083352,-.033952,
.087981,-.018962,
.089937,-.003396,
.089161,.012273,
.085675,.027569,
.079586,.042027,
.07619,.04791,
.07256,.04427,
0.0*
4,1,16,.04427,-.07256,
.030998,-.079145,
.016783,-.083325,
.002059,-.084974,
-.012728,-.08404,
-.027128,-.080553,
-.040704,-.074619,
-.04427,-.07256,
-.04791,-.07619,
-.033952,-.083352,
-.018962,-.087981,
-.003396,-.089937,
.012273,-.089161,
.027569,-.085675,
.042027,-.079586,
.04791,-.07619,
.04427,-.07256,
0.0*
4,1,16,-.07256,-.04427,
-.079145,-.030998,
-.083325,-.016783,
-.084974,-.002059,
-.08404,.012728,
-.080553,.027128,
-.074619,.040704,
-.07256,.04427,
-.07619,.04791,
-.083352,.033952,
-.087981,.018962,
-.089937,.003396,
-.089161,-.012273,
-.085675,-.027569,
-.079586,-.042027,
-.07619,-.04791,
-.07256,-.04427,
0.0*
4,1,16,-.04427,.07256,
-.030998,.079145,
-.016783,.083325,
-.002059,.084974,
.012728,.08404,
.027128,.080553,
.040704,.074619,
.04427,.07256,
.04791,.07619,
.033952,.083352,
.018962,.087981,
.003396,.089937,
-.012273,.089161,
-.027569,.085675,
-.042027,.079586,
-.04791,.07619,
-.04427,.07256,
0.0*
%
%ADD11MACRO11*%
%ADD21C,.02*%
%ADD22C,.006*%
%ADD25C,.06804*%
%ADD24C,.08704*%
%ADD26C,.08904*%
%ADD23O,.04824X.09264*%
G75*
%LPD*%
G75*
G36*
G01X-6000Y-6000D02*
X355409D01*
Y369425D01*
X-6000D01*
Y-6000D01*
G37*
%LPC*%
G75*
G36*
G01X223819Y1904D02*
G02X217849Y7874I0J5970D01*
G01Y258071D01*
G03X208071Y267849I-9778J0D01*
G01X7874D01*
G02X1904Y273819I0J5970D01*
G01Y355551D01*
G02X7874Y361521I5970J0D01*
G01X341535D01*
G02X347505Y355551I0J-5970D01*
G01Y278779D01*
G02X347441Y278715I-64J0D01*
G01X339566D01*
G03X335694Y274843I1J-3873D01*
G01Y219567D01*
G03X339567Y215694I3873J0D01*
G01X347441D01*
G02X347505Y215630I0J-64D01*
G01Y195925D01*
G02X347441Y195861I-64J0D01*
G01X321062D01*
G03X317190Y191989I1J-3873D01*
G01Y175256D01*
G03X321063Y171383I3873J0D01*
G01X323938D01*
G02X324212Y170691I0J-400D01*
G03X323732Y169587I1032J-1105D01*
G01Y166437D01*
G03X325720Y165002I1512J0D01*
G02X326246Y164623I126J-379D01*
G01Y161952D01*
G02X325720Y161573I-400J0D01*
G03X323732Y160138I-476J-1435D01*
G01Y156988D01*
G03X325720Y155553I1512J0D01*
G02X326246Y155174I126J-379D01*
G01Y152502D01*
G02X325720Y152122I-400J0D01*
G03X323734Y150689I-476J-1433D01*
G01Y147540D01*
G03X325720Y146107I1510J0D01*
G02X326246Y145727I126J-380D01*
G01Y111558D01*
G02X325720Y111179I-400J0D01*
G03X323732Y109744I-476J-1435D01*
G01Y106595D01*
G03X325720Y105160I1512J0D01*
G02X326246Y104781I126J-379D01*
G01Y102110D01*
G02X325720Y101731I-400J0D01*
G03X323732Y100296I-476J-1435D01*
G01Y97146D01*
G03X325720Y95711I1512J0D01*
G02X326246Y95332I126J-379D01*
G01Y92661D01*
G02X325720Y92282I-400J0D01*
G03X323732Y90847I-476J-1435D01*
G01Y87697D01*
G03X325720Y86262I1512J0D01*
G02X326246Y85883I126J-379D01*
G01Y83212D01*
G02X325720Y82833I-400J0D01*
G03X323732Y81399I-476J-1435D01*
G01Y78248D01*
G03X325720Y76813I1512J0D01*
G02X326246Y76434I126J-379D01*
G01Y73763D01*
G02X325720Y73384I-400J0D01*
G03X323732Y71949I-476J-1435D01*
G01Y68799D01*
G03X325720Y67364I1512J0D01*
G02X326246Y66985I126J-379D01*
G01Y64314D01*
G02X325720Y63935I-400J0D01*
G03X323732Y62501I-476J-1435D01*
G01Y59351D01*
G03X325720Y57916I1512J0D01*
G02X326246Y57537I126J-379D01*
G01Y46004D01*
G02X326181Y45939I-65J0D01*
G01X321062D01*
G03X317190Y42067I1J-3873D01*
G01Y25334D01*
G03X321062Y21462I3873J1D01*
G01X347441D01*
G02X347505Y21398I0J-64D01*
G01Y1968D01*
G02X347441Y1904I-64J0D01*
G01X223819D01*
G37*
%LPD*%
G75*
G36*
G01X289288Y198561D02*
G02X293312I2012J0D01*
G01Y195360D01*
G02X289288Y195361I-2012J1D01*
G01Y198561D01*
G37*
G36*
G01X300388Y137043D02*
G02X305212I2412J0D01*
G01Y132642D01*
G02X300388Y132643I-2412J1D01*
G01Y137043D01*
G37*
G36*
G01X292988Y89899D02*
G02X297012I2012J0D01*
G01Y86698D01*
G02X292988Y86699I-2012J1D01*
G01Y89899D01*
G37*
G36*
G01X277512Y222811D02*
Y218371D01*
G02X272688Y218372I-2412J1D01*
G01Y222812D01*
G02X277512Y222811I2412J-1D01*
G37*
G36*
G01X275512Y211000D02*
Y206560D01*
G02X270688Y206561I-2412J1D01*
G01Y211001D01*
G02X275512Y211000I2412J-1D01*
G37*
G36*
G01Y102339D02*
Y97898D01*
G02X270688Y97899I-2412J1D01*
G01Y102339D01*
G02X275512I2412J0D01*
G37*
G36*
G01X260750Y65189D02*
X259311Y63750D01*
X232689D01*
X231250Y65189D01*
Y306811D01*
X232689Y308250D01*
X242013D01*
X242033Y308254D01*
G02X242967I467J-2254D01*
G01X242987Y308250D01*
X246013D01*
X246033Y308254D01*
G02X246967I467J-2254D01*
G01X246987Y308250D01*
X250013D01*
X250033Y308254D01*
G02X250967I467J-2254D01*
G01X250987Y308250D01*
X259311D01*
X260750Y306811D01*
Y168921D01*
G02Y167079I-2000J-921D01*
G01Y65189D01*
G37*
G54D25*
X265551Y143464D03*
Y252126D03*
G54D24*
Y64724D03*
Y173386D03*
X311614Y31870D03*
G54D26*
Y185414D03*
G54D23*
X275100Y111930D03*
%LPC*%
G75*
G36*
G01X259250Y65811D02*
X258689Y65250D01*
X233311D01*
X232750Y65811D01*
Y306189D01*
X233311Y306750D01*
X258689D01*
X259250Y306189D01*
Y65811D01*
G37*
%LPD*%
G75*
G54D15*
X95000Y277500D03*
X99000D03*
X106500D03*
X92500Y295000D03*
X106137Y286000D03*
X100000Y288500D03*
X92500Y298500D03*
Y309000D03*
X107000Y311500D03*
Y308000D03*
X100250Y313200D03*
X103500Y317000D03*
Y321000D03*
X91500Y312500D03*
X96750Y328500D03*
X100500Y347289D03*
X121500Y276500D03*
X118000D03*
X114500D03*
X110500Y277500D03*
X121456Y289154D03*
X112500Y289000D03*
X108000Y295000D03*
Y298500D03*
X115000Y305000D03*
X119000D03*
X108000Y303100D03*
X120120Y315000D03*
X116500D03*
X109500Y334500D03*
X113000D03*
X117000D03*
X121000D03*
X125000Y277000D03*
X128500Y282500D03*
X126000Y287000D03*
X130000Y298500D03*
X215064Y316100D03*
X236805Y146452D03*
X237000Y156000D03*
Y159780D03*
Y152500D03*
X236500Y168500D03*
X225000Y169500D03*
X237000Y164250D03*
X252000Y151500D03*
Y155000D03*
Y160500D03*
X251500Y164500D03*
X263000Y96500D03*
Y88500D03*
Y81338D03*
Y84838D03*
Y104000D03*
X262819Y100157D03*
X268140Y161221D03*
X258750Y168000D03*
X263000Y190000D03*
Y193500D03*
Y205000D03*
Y197000D03*
Y212500D03*
X262819Y208819D03*
X263000Y240315D03*
X275100Y109710D03*
X273100Y102299D03*
Y97899D03*
X275100Y114110D03*
X279000Y166000D03*
X273100Y210961D03*
Y206561D03*
X275100Y222772D03*
Y218372D03*
X295000Y86699D03*
Y89899D03*
X301000Y125000D03*
X292000Y126000D03*
X302800Y137043D03*
Y132643D03*
X290500Y154250D03*
X296500Y157500D03*
X290500Y150750D03*
X291000Y169500D03*
X291300Y195361D03*
Y198561D03*
X325244Y49902D03*
Y53051D03*
Y62500D03*
Y59351D03*
Y78248D03*
Y68799D03*
Y71949D03*
Y97146D03*
Y87697D03*
Y90847D03*
Y81398D03*
Y106595D03*
Y109744D03*
Y100296D03*
Y156988D03*
Y160138D03*
Y150689D03*
Y147540D03*
Y166437D03*
Y169587D03*
G54D14*
X72000Y286000D03*
Y290000D03*
X58000Y310689D03*
X79000Y344000D03*
Y348000D03*
X138500Y299500D03*
X134500Y307500D03*
X138500Y303500D03*
Y307500D03*
X137500Y324500D03*
X142500Y299500D03*
Y303500D03*
Y307500D03*
X141811Y324500D03*
X145811D03*
X153811D03*
X149811D03*
X162311Y293000D03*
X160811Y310000D03*
X169811Y309500D03*
X172311Y305500D03*
X157811Y324500D03*
X161811D03*
X169811D03*
X165811D03*
X169811Y313500D03*
X176311Y294000D03*
X181061Y297750D03*
X176168Y305500D03*
X195811Y296000D03*
X200811Y308000D03*
Y311000D03*
Y317000D03*
Y314000D03*
X218000Y292000D03*
X215811Y300000D03*
X222311Y325000D03*
X218311D03*
X230000Y96500D03*
X225000Y205000D03*
X222911Y287089D03*
X249000Y260000D03*
X262920Y131653D03*
X273000Y92283D03*
X299500Y46000D03*
X303500D03*
X296500Y61000D03*
X300500D03*
X301500Y49000D03*
X297500D03*
X295500Y52000D03*
X299500D03*
X295500Y110000D03*
X295311Y127600D03*
X304500Y123820D03*
X301711Y245000D03*
G54D17*
X265551Y143464D03*
Y252126D03*
G54D16*
Y64724D03*
Y173386D03*
X311614Y31870D03*
G54D20*
Y185414D03*
G54D18*
X302000Y290500D03*
Y300500D03*
G54D12*
X10000Y330000D03*
Y345000D03*
Y360000D03*
X40000Y270000D03*
Y285000D03*
Y300000D03*
Y330000D03*
Y345000D03*
X25000Y360000D03*
X40000D03*
X55000Y270000D03*
Y285000D03*
Y360000D03*
X70000Y270000D03*
Y360000D03*
X85000Y270000D03*
Y360000D03*
X100000Y270000D03*
X103000Y277500D03*
X96750Y313250D03*
X103750Y313200D03*
X100500Y335689D03*
X100000Y360000D03*
X122100Y280750D03*
X122000Y301000D03*
X115000Y360000D03*
X124000Y315000D03*
X138000Y341500D03*
X130000Y360000D03*
X138000Y345500D03*
X140500Y281000D03*
X146500Y303500D03*
X150500D03*
X146500Y307500D03*
X150500D03*
X155000Y301350D03*
X149811Y341500D03*
X141811D03*
X145811D03*
X153811D03*
X145000Y360000D03*
X149811Y345500D03*
X141811D03*
X145811D03*
X153811D03*
X164811Y304000D03*
X165811Y341500D03*
X157811D03*
X161811D03*
X169811D03*
X160000Y360000D03*
X165811Y345500D03*
X169811D03*
X157811D03*
X161811D03*
X185811Y304200D03*
Y310500D03*
X181811D03*
Y318500D03*
X185811Y314500D03*
Y326500D03*
Y322500D03*
Y318500D03*
X181811Y326500D03*
Y322500D03*
Y314500D03*
X184500Y334000D03*
Y338000D03*
X175000Y360000D03*
X189811Y310500D03*
Y318500D03*
Y322500D03*
Y326500D03*
Y314500D03*
X190000Y360000D03*
X205000D03*
X220000D03*
X225000Y35000D03*
Y50000D03*
Y80000D03*
Y65000D03*
X230000Y75000D03*
Y67000D03*
Y71000D03*
X225000Y95000D03*
Y110000D03*
X230000Y126000D03*
Y130000D03*
Y122000D03*
Y138500D03*
Y142500D03*
Y134500D03*
X225000Y160250D03*
Y149250D03*
Y164250D03*
X230000Y175500D03*
Y179500D03*
Y183500D03*
Y243000D03*
Y234500D03*
Y238500D03*
Y230500D03*
Y247000D03*
Y251000D03*
X237500Y340000D03*
Y344000D03*
Y336000D03*
X235000Y360000D03*
X255000Y5000D03*
Y35000D03*
X247000Y68838D03*
Y72838D03*
X251000Y68838D03*
Y72838D03*
Y88500D03*
X247000Y123838D03*
X251000D03*
X247000Y127838D03*
X251000D03*
X247000Y136338D03*
Y140838D03*
X251000D03*
Y136338D03*
Y177500D03*
X247000D03*
X251000Y181500D03*
X247000D03*
X251000Y197000D03*
Y245000D03*
X247000D03*
X251000Y236500D03*
X247000D03*
X251000Y232500D03*
X247000D03*
X251000Y249500D03*
X247000D03*
X242500Y294000D03*
X246500D03*
X250500D03*
X242500Y306000D03*
Y302000D03*
Y298000D03*
X246500Y306000D03*
Y302000D03*
Y298000D03*
X250500D03*
Y302000D03*
Y306000D03*
X241500Y336000D03*
Y344000D03*
Y340000D03*
X250000Y360000D03*
X270000Y5000D03*
Y35000D03*
X269650Y97899D03*
X271650Y109710D03*
X269650Y102299D03*
X271650Y114110D03*
X271250Y138750D03*
X267700Y153250D03*
X269650Y210961D03*
Y206561D03*
X271650Y222772D03*
Y218372D03*
X265000Y270000D03*
Y285000D03*
X271500Y294000D03*
X267500D03*
X271500Y306000D03*
Y302000D03*
Y298000D03*
X267500D03*
Y302000D03*
Y306000D03*
X260500Y340000D03*
Y344000D03*
Y336000D03*
X256500D03*
Y344000D03*
Y340000D03*
X265000Y360000D03*
X282500Y5000D03*
X272500Y20000D03*
X285000Y32500D03*
X275500Y63346D03*
X280000Y71614D03*
Y67677D03*
X280169Y126732D03*
Y120826D03*
X275768Y144842D03*
X280169Y138543D03*
Y132637D03*
X278860Y162250D03*
X280000Y176339D03*
X275500Y172008D03*
X280000Y180276D03*
X273500Y194055D03*
Y199961D03*
X273600Y240250D03*
X280169Y247205D03*
X275768Y253504D03*
X280000Y270000D03*
X275500Y294000D03*
X280000Y285000D03*
X275500Y298000D03*
Y302000D03*
Y306000D03*
X280000Y300000D03*
Y315000D03*
X295000Y5000D03*
X300000Y20000D03*
Y35000D03*
X304565Y61142D03*
Y96142D03*
X304500Y92000D03*
X291500Y97204D03*
X291550Y91299D03*
X291500Y85393D03*
X295500Y100000D03*
X291500Y109960D03*
Y101960D03*
Y114921D03*
X300500Y129100D03*
X299300Y137043D03*
X304565Y141142D03*
X299300Y132643D03*
X302000Y157500D03*
X292000Y181500D03*
X294750Y195261D03*
X295500Y208461D03*
X294750Y198661D03*
X291500Y210961D03*
Y205866D03*
Y218461D03*
Y223583D03*
Y241299D03*
Y229488D03*
Y235394D03*
X295000Y270000D03*
Y285000D03*
Y300000D03*
Y315000D03*
X315000Y5000D03*
Y20000D03*
Y40000D03*
X313000Y179500D03*
X310000Y225000D03*
Y240000D03*
Y255000D03*
Y270000D03*
Y285000D03*
Y300000D03*
Y315000D03*
Y330000D03*
Y360000D03*
Y345000D03*
X325244Y56201D03*
Y75099D03*
Y65650D03*
Y93996D03*
Y84548D03*
Y112894D03*
Y103445D03*
Y128642D03*
Y119193D03*
Y144390D03*
Y138091D03*
Y153839D03*
Y163288D03*
X324302Y203977D03*
X325000Y225000D03*
Y240000D03*
Y255000D03*
Y270000D03*
Y285000D03*
Y300000D03*
Y315000D03*
Y330000D03*
Y360000D03*
Y345000D03*
X345000Y5000D03*
Y20000D03*
X340000Y285000D03*
Y300000D03*
Y315000D03*
Y330000D03*
Y360000D03*
Y345000D03*
G54D19*
X302000Y310500D03*
G54D10*
X26087Y-114844D03*
X26435Y373984D03*
X175335Y62719D03*
Y189062D03*
X547104Y69007D03*
Y195351D03*
X696192Y373984D03*
G54D13*
X52500Y325189D03*
Y331189D03*
X59500Y294189D03*
X64500Y309589D03*
X59500Y299939D03*
X71500Y315689D03*
X67900D03*
X72000Y336689D03*
X89000Y295189D03*
Y291189D03*
Y287189D03*
Y283189D03*
Y303689D03*
Y299689D03*
X75100Y315689D03*
X89000Y329189D03*
Y333189D03*
G54D11*
X25596Y316176D03*
X237013Y17712D03*
X287407Y345704D03*
%LPC*%
G75*
G54D21*
G01X-176139Y-183003D02*
G02I-12000J0D01*
G01X-181289D02*
G02I-6850J0D01*
G01X-172139D02*
X-204139D01*
G01X-188139Y-199003D02*
Y-167003D01*
G01X-172139Y-199003D02*
Y-279003D01*
G01D02*
X1178561D01*
G01X-172139Y-234503D02*
X1178561D01*
G01X-172139Y-199003D02*
X1178561D01*
G01X391061D02*
Y-279003D01*
G01X528561Y-199003D02*
Y-279003D01*
G01X643561Y-199003D02*
Y-279003D01*
G01X811061Y-199003D02*
Y-279003D01*
G01X981061Y-199003D02*
Y-279003D01*
G01X1178561Y-199003D02*
Y-279003D01*
G01X1210561Y-183003D02*
X1178561D01*
G01X1206561D02*
G02I-12000J0D01*
G01X1201411D02*
G02I-6850J0D01*
G01X1194561Y-199003D02*
Y-167003D01*
G54D22*
G01X-148956Y-251503D02*
Y-269003D01*
X-140222D01*
G01X-127089Y-257337D02*
Y-269003D01*
G01Y-252670D02*
X-127526Y-252378D01*
Y-251795D01*
X-127089Y-251503D01*
X-126652Y-251795D01*
Y-252378D01*
X-127089Y-252670D01*
G01X-112646Y-273378D02*
X-111117Y-274545D01*
X-109371Y-274836D01*
X-107843Y-274545D01*
X-106532Y-273087D01*
X-105659Y-271045D01*
Y-257337D01*
G01Y-259670D02*
X-106532Y-258503D01*
X-107843Y-257628D01*
X-109371Y-257337D01*
X-111117Y-257920D01*
X-112209Y-259086D01*
X-113083Y-261128D01*
X-113519Y-263170D01*
X-113301Y-264920D01*
X-112427Y-266962D01*
X-111117Y-268420D01*
X-109371Y-269003D01*
X-108061Y-268711D01*
X-106532Y-267545D01*
X-105659Y-266379D01*
G01X-95801Y-269003D02*
Y-251503D01*
G01Y-259961D02*
X-94709Y-258503D01*
X-93617Y-257628D01*
X-91871Y-257337D01*
X-90561Y-257628D01*
X-89032Y-258795D01*
X-88377Y-260545D01*
Y-269003D01*
G01X-74589Y-251503D02*
Y-269003D01*
G01X-77646Y-257337D02*
X-71532D01*
G01X-60801Y-269003D02*
Y-257337D01*
G01Y-260253D02*
X-59927Y-258795D01*
X-58617Y-257628D01*
X-56871Y-257337D01*
X-55343Y-257628D01*
X-54032Y-258795D01*
X-53377Y-260836D01*
Y-269003D01*
G01X-39589Y-257337D02*
Y-269003D01*
G01Y-252670D02*
X-40026Y-252378D01*
Y-251795D01*
X-39589Y-251503D01*
X-39152Y-251795D01*
Y-252378D01*
X-39589Y-252670D01*
G01X-25801Y-269003D02*
Y-257337D01*
G01Y-260253D02*
X-24927Y-258795D01*
X-23617Y-257628D01*
X-21871Y-257337D01*
X-20343Y-257628D01*
X-19032Y-258795D01*
X-18377Y-260836D01*
Y-269003D01*
G01X-7646Y-273378D02*
X-6117Y-274545D01*
X-4371Y-274836D01*
X-2843Y-274545D01*
X-1532Y-273087D01*
X-659Y-271045D01*
Y-257337D01*
G01Y-259670D02*
X-1532Y-258503D01*
X-2843Y-257628D01*
X-4371Y-257337D01*
X-6117Y-257920D01*
X-7209Y-259086D01*
X-8083Y-261128D01*
X-8519Y-263170D01*
X-8301Y-264920D01*
X-7427Y-266962D01*
X-6117Y-268420D01*
X-4371Y-269003D01*
X-3061Y-268711D01*
X-1532Y-267545D01*
X-659Y-266379D01*
G01X26044Y-269003D02*
Y-251503D01*
X31284D01*
X33031Y-252378D01*
X34341Y-254420D01*
X34778Y-256753D01*
X34341Y-259086D01*
X33249Y-260836D01*
X31284Y-261712D01*
X26044D01*
G01X42452Y-251503D02*
X47911Y-269003D01*
X53370Y-251503D01*
G01X65411D02*
Y-269003D01*
G01X60389Y-251503D02*
X70433D01*
G01X94734Y-269003D02*
Y-251503D01*
X100411Y-266086D01*
X106088Y-251503D01*
Y-269003D01*
G01X117911Y-269586D02*
X117474Y-269295D01*
Y-268711D01*
X117911Y-268420D01*
X118348Y-268711D01*
Y-269295D01*
X117911Y-269586D01*
G01X131263Y-254420D02*
X132573Y-252670D01*
X134101Y-251795D01*
X135848Y-251503D01*
X138031Y-252086D01*
X139559Y-253545D01*
X139996Y-255294D01*
X139778Y-257045D01*
X138904Y-258503D01*
X134538Y-261420D01*
X132573Y-263461D01*
X131263Y-266379D01*
X130826Y-269003D01*
X139996D01*
G01X164952D02*
X170411Y-251503D01*
X175870Y-269003D01*
G01X173904Y-262878D02*
X166917D01*
G01X191841Y-251503D02*
Y-269003D01*
G01Y-266379D02*
X190968Y-267837D01*
X189657Y-268711D01*
X188129Y-269003D01*
X186383Y-268420D01*
X185073Y-266962D01*
X184199Y-265212D01*
X183981Y-263170D01*
X184199Y-261128D01*
X185073Y-259378D01*
X186383Y-257920D01*
X188129Y-257337D01*
X189657Y-257628D01*
X190749Y-258212D01*
X191841Y-259378D01*
G01X209341Y-269003D02*
Y-257337D01*
G01Y-259378D02*
X208468Y-258212D01*
X207157Y-257628D01*
X205629Y-257337D01*
X204101Y-257920D01*
X202791Y-259086D01*
X201917Y-260836D01*
X201481Y-263170D01*
X201917Y-265503D01*
X202791Y-267253D01*
X204101Y-268420D01*
X205629Y-269003D01*
X207157Y-268711D01*
X208468Y-267837D01*
X209341Y-266670D01*
G01X218981Y-274836D02*
Y-257337D01*
G01Y-259961D02*
X220073Y-258503D01*
X221164Y-257628D01*
X222911Y-257337D01*
X224439Y-257628D01*
X225968Y-259086D01*
X226623Y-261128D01*
X226841Y-263170D01*
X226623Y-265212D01*
X225968Y-267253D01*
X224657Y-268420D01*
X222911Y-269003D01*
X221383Y-268711D01*
X219854Y-267837D01*
X218981Y-266670D01*
G01X240411Y-251503D02*
Y-269003D01*
G01X237354Y-257337D02*
X243468D01*
G01X257911Y-269003D02*
X256601Y-268711D01*
X255291Y-267545D01*
X254417Y-265503D01*
X253981Y-263170D01*
X254417Y-260836D01*
X255291Y-258795D01*
X256601Y-257628D01*
X257911Y-257337D01*
X259221Y-257628D01*
X260531Y-258795D01*
X261404Y-260836D01*
X261623Y-263170D01*
X261404Y-265503D01*
X260531Y-267545D01*
X259221Y-268711D01*
X257911Y-269003D01*
G01X272354D02*
Y-257337D01*
G01Y-259670D02*
X273446Y-258503D01*
X274538Y-257628D01*
X276066Y-257337D01*
X277157Y-257628D01*
X278468Y-258503D01*
G01X315214Y-252962D02*
X313904Y-252086D01*
X312376Y-251503D01*
X310629D01*
X308664Y-252378D01*
X307136Y-253836D01*
X306044Y-255587D01*
X305171Y-258503D01*
X304952Y-261128D01*
X305389Y-263753D01*
X306044Y-265503D01*
X307354Y-267253D01*
X308883Y-268420D01*
X310411Y-269003D01*
X311939D01*
X313468Y-268420D01*
X314778Y-267545D01*
X315870Y-266379D01*
G01X331841Y-269003D02*
Y-257337D01*
G01Y-259378D02*
X330968Y-258212D01*
X329657Y-257628D01*
X328129Y-257337D01*
X326601Y-257920D01*
X325291Y-259086D01*
X324417Y-260836D01*
X323981Y-263170D01*
X324417Y-265503D01*
X325291Y-267253D01*
X326601Y-268420D01*
X328129Y-269003D01*
X329657Y-268711D01*
X330968Y-267837D01*
X331841Y-266670D01*
G01X342354Y-269003D02*
Y-257337D01*
G01Y-259670D02*
X343446Y-258503D01*
X344538Y-257628D01*
X346066Y-257337D01*
X347157Y-257628D01*
X348468Y-258503D01*
G01X366841Y-251503D02*
Y-269003D01*
G01Y-266379D02*
X365968Y-267837D01*
X364657Y-268711D01*
X363129Y-269003D01*
X361383Y-268420D01*
X360073Y-266962D01*
X359199Y-265212D01*
X358981Y-263170D01*
X359199Y-261128D01*
X360073Y-259378D01*
X361383Y-257920D01*
X363129Y-257337D01*
X364657Y-257628D01*
X365749Y-258212D01*
X366841Y-259378D01*
G01X68484Y-224003D02*
Y-206503D01*
X74161Y-221086D01*
X79838Y-206503D01*
Y-224003D01*
G01X91661D02*
X90351Y-223711D01*
X89041Y-222545D01*
X88167Y-220503D01*
X87731Y-218170D01*
X88167Y-215836D01*
X89041Y-213795D01*
X90351Y-212628D01*
X91661Y-212337D01*
X92971Y-212628D01*
X94281Y-213795D01*
X95154Y-215836D01*
X95373Y-218170D01*
X95154Y-220503D01*
X94281Y-222545D01*
X92971Y-223711D01*
X91661Y-224003D01*
G01X113091Y-206503D02*
Y-224003D01*
G01Y-221379D02*
X112218Y-222837D01*
X110907Y-223711D01*
X109379Y-224003D01*
X107633Y-223420D01*
X106323Y-221962D01*
X105449Y-220212D01*
X105231Y-218170D01*
X105449Y-216128D01*
X106323Y-214378D01*
X107633Y-212920D01*
X109379Y-212337D01*
X110907Y-212628D01*
X111999Y-213212D01*
X113091Y-214378D01*
G01X123386Y-216128D02*
X130373D01*
X129718Y-214086D01*
X128626Y-212920D01*
X127098Y-212337D01*
X125569Y-212628D01*
X124259Y-213503D01*
X123386Y-215545D01*
X122949Y-217295D01*
Y-219045D01*
X123386Y-220795D01*
X124478Y-222545D01*
X125788Y-223711D01*
X127316Y-224003D01*
X128844Y-223420D01*
X130373Y-221670D01*
G01X144161Y-224003D02*
Y-206503D01*
G01X424761Y-269003D02*
Y-251503D01*
X422141Y-255003D01*
G01Y-269003D02*
X427381D01*
G01X437458Y-266379D02*
X438767Y-267837D01*
X440296Y-268711D01*
X442261Y-269003D01*
X444226Y-268420D01*
X445754Y-267253D01*
X446846Y-265212D01*
X447064Y-262878D01*
X446628Y-260545D01*
X445536Y-259086D01*
X444007Y-257920D01*
X442479Y-257628D01*
X440951Y-257920D01*
X438986Y-259086D01*
X439641Y-251503D01*
X445536D01*
G01X459324Y-269003D02*
X459761Y-265212D01*
X460416Y-262003D01*
X461289Y-259086D01*
X462381Y-255878D01*
X464128Y-251503D01*
X455394D01*
G01X472458Y-266379D02*
X473767Y-267837D01*
X475296Y-268711D01*
X477261Y-269003D01*
X479226Y-268420D01*
X480754Y-267253D01*
X481846Y-265212D01*
X482064Y-262878D01*
X481628Y-260545D01*
X480536Y-259086D01*
X479007Y-257920D01*
X477479Y-257628D01*
X475951Y-257920D01*
X473986Y-259086D01*
X474641Y-251503D01*
X480536D01*
G01X494761D02*
X493014Y-252086D01*
X491704Y-253545D01*
X490831Y-255294D01*
X490176Y-257628D01*
X489958Y-260253D01*
X490176Y-262878D01*
X490831Y-265212D01*
X491704Y-266962D01*
X493014Y-268420D01*
X494761Y-269003D01*
X496507Y-268420D01*
X497818Y-266962D01*
X498691Y-265212D01*
X499346Y-262878D01*
X499564Y-260253D01*
X499346Y-257628D01*
X498691Y-255294D01*
X497818Y-253545D01*
X496507Y-252086D01*
X494761Y-251503D01*
G01X411644Y-224003D02*
Y-206503D01*
X416884D01*
X418631Y-207378D01*
X419941Y-209420D01*
X420378Y-211753D01*
X419941Y-214086D01*
X418849Y-215836D01*
X416884Y-216712D01*
X411644D01*
G01X438314Y-207962D02*
X437004Y-207086D01*
X435476Y-206503D01*
X433729D01*
X431764Y-207378D01*
X430236Y-208836D01*
X429144Y-210587D01*
X428271Y-213503D01*
X428052Y-216128D01*
X428489Y-218753D01*
X429144Y-220503D01*
X430454Y-222253D01*
X431983Y-223420D01*
X433511Y-224003D01*
X435039D01*
X436568Y-223420D01*
X437878Y-222545D01*
X438970Y-221379D01*
G01X452757Y-214670D02*
X453631Y-213795D01*
X454286Y-212337D01*
X454723Y-210294D01*
X454286Y-208545D01*
X453413Y-207378D01*
X451884Y-206503D01*
X445989D01*
Y-224003D01*
X453194D01*
X454723Y-222837D01*
X455596Y-221086D01*
X456033Y-219045D01*
X455596Y-217003D01*
X454286Y-215253D01*
X452757Y-214670D01*
X445989D01*
G01X461961Y-229836D02*
X475061D01*
G01X480989Y-224003D02*
Y-206503D01*
X491033Y-224003D01*
Y-206503D01*
G01X503511Y-224003D02*
X501764Y-223711D01*
X500236Y-222545D01*
X498926Y-220795D01*
X498052Y-218753D01*
X497616Y-216420D01*
Y-214086D01*
X498052Y-211753D01*
X498926Y-209711D01*
X500236Y-207962D01*
X501764Y-206795D01*
X503511Y-206503D01*
X505257Y-206795D01*
X506786Y-207962D01*
X508096Y-209711D01*
X508970Y-211753D01*
X509406Y-214086D01*
Y-216420D01*
X508970Y-218753D01*
X508096Y-220795D01*
X506786Y-222545D01*
X505257Y-223711D01*
X503511Y-224003D01*
G01X554352Y-206503D02*
X559811Y-224003D01*
X565270Y-206503D01*
G01X581678Y-224003D02*
X572944D01*
Y-206503D01*
X581678D01*
G01X578184Y-214961D02*
X572944D01*
G01X590444Y-224003D02*
Y-206503D01*
X595903D01*
X597649Y-207378D01*
X598741Y-208545D01*
X599178Y-210878D01*
X598741Y-213212D01*
X597431Y-214670D01*
X595903Y-215545D01*
X590444D01*
G01X595903D02*
X599178Y-224003D01*
G01X612311Y-224586D02*
X611874Y-224295D01*
Y-223711D01*
X612311Y-223420D01*
X612748Y-223711D01*
Y-224295D01*
X612311Y-224586D01*
G01X586061Y-269003D02*
Y-251503D01*
X583441Y-255003D01*
G01Y-269003D02*
X588681D01*
G01X687894Y-251503D02*
Y-269003D01*
X696628D01*
G01X712381D02*
Y-251503D01*
X704302Y-264045D01*
X715220D01*
G01X728571Y-260253D02*
X732938D01*
Y-265503D01*
X731628Y-267253D01*
X730099Y-268420D01*
X727916Y-269003D01*
X725733Y-268420D01*
X724204Y-267253D01*
X722894Y-265503D01*
X722021Y-263461D01*
X721584Y-261128D01*
Y-259086D01*
X722021Y-257337D01*
X722894Y-255294D01*
X724204Y-253545D01*
X725514Y-252378D01*
X727261Y-251503D01*
X728789D01*
X730536Y-252086D01*
X731846Y-253253D01*
G01X739739Y-269003D02*
Y-251503D01*
X749783Y-269003D01*
Y-251503D01*
G01X757458Y-269003D02*
Y-251503D01*
X761824D01*
X763571Y-252378D01*
X764881Y-253545D01*
X765973Y-255294D01*
X766846Y-257337D01*
X767064Y-260253D01*
X766846Y-263170D01*
X765973Y-265212D01*
X764881Y-266962D01*
X763571Y-268128D01*
X761824Y-269003D01*
X757458D01*
G01X687894Y-206503D02*
Y-224003D01*
X696628D01*
G01X713691D02*
Y-212337D01*
G01Y-214378D02*
X712818Y-213212D01*
X711507Y-212628D01*
X709979Y-212337D01*
X708451Y-212920D01*
X707141Y-214086D01*
X706267Y-215836D01*
X705831Y-218170D01*
X706267Y-220503D01*
X707141Y-222253D01*
X708451Y-223420D01*
X709979Y-224003D01*
X711507Y-223711D01*
X712818Y-222837D01*
X713691Y-221670D01*
G01X722676Y-229253D02*
X723986Y-229836D01*
X725733Y-229253D01*
X726824Y-228087D01*
X727698Y-226628D01*
X729007Y-221962D01*
X731846Y-212337D01*
G01X724859D02*
X729007Y-221962D01*
G01X741486Y-216128D02*
X748473D01*
X747818Y-214086D01*
X746726Y-212920D01*
X745198Y-212337D01*
X743669Y-212628D01*
X742359Y-213503D01*
X741486Y-215545D01*
X741049Y-217295D01*
Y-219045D01*
X741486Y-220795D01*
X742578Y-222545D01*
X743888Y-223711D01*
X745416Y-224003D01*
X746944Y-223420D01*
X748473Y-221670D01*
G01X759204Y-224003D02*
Y-212337D01*
G01Y-214670D02*
X760296Y-213503D01*
X761388Y-212628D01*
X762916Y-212337D01*
X764007Y-212628D01*
X765318Y-213503D01*
G01X830008Y-224003D02*
Y-206503D01*
X834374D01*
X836121Y-207378D01*
X837431Y-208545D01*
X838523Y-210294D01*
X839396Y-212337D01*
X839614Y-215253D01*
X839396Y-218170D01*
X838523Y-220212D01*
X837431Y-221962D01*
X836121Y-223128D01*
X834374Y-224003D01*
X830008D01*
G01X849036Y-216128D02*
X856023D01*
X855368Y-214086D01*
X854276Y-212920D01*
X852748Y-212337D01*
X851219Y-212628D01*
X849909Y-213503D01*
X849036Y-215545D01*
X848599Y-217295D01*
Y-219045D01*
X849036Y-220795D01*
X850128Y-222545D01*
X851438Y-223711D01*
X852966Y-224003D01*
X854494Y-223420D01*
X856023Y-221670D01*
G01X866536Y-221962D02*
X867628Y-223128D01*
X869156Y-224003D01*
X870466D01*
X871776Y-223420D01*
X872649Y-222545D01*
X873086Y-221379D01*
X872868Y-219628D01*
X871994Y-218753D01*
X868064Y-217003D01*
X867191Y-214961D01*
X867628Y-213503D01*
X868501Y-212628D01*
X869811Y-212337D01*
X871121Y-212628D01*
X872431Y-213503D01*
G01X887311Y-212337D02*
Y-224003D01*
G01Y-207670D02*
X886874Y-207378D01*
Y-206795D01*
X887311Y-206503D01*
X887748Y-206795D01*
Y-207378D01*
X887311Y-207670D01*
G01X901754Y-228378D02*
X903283Y-229545D01*
X905029Y-229836D01*
X906557Y-229545D01*
X907868Y-228087D01*
X908741Y-226045D01*
Y-212337D01*
G01Y-214670D02*
X907868Y-213503D01*
X906557Y-212628D01*
X905029Y-212337D01*
X903283Y-212920D01*
X902191Y-214086D01*
X901317Y-216128D01*
X900881Y-218170D01*
X901099Y-219920D01*
X901973Y-221962D01*
X903283Y-223420D01*
X905029Y-224003D01*
X906339Y-223711D01*
X907868Y-222545D01*
X908741Y-221379D01*
G01X918599Y-224003D02*
Y-212337D01*
G01Y-215253D02*
X919473Y-213795D01*
X920783Y-212628D01*
X922529Y-212337D01*
X924057Y-212628D01*
X925368Y-213795D01*
X926023Y-215836D01*
Y-224003D01*
G01X936536Y-216128D02*
X943523D01*
X942868Y-214086D01*
X941776Y-212920D01*
X940248Y-212337D01*
X938719Y-212628D01*
X937409Y-213503D01*
X936536Y-215545D01*
X936099Y-217295D01*
Y-219045D01*
X936536Y-220795D01*
X937628Y-222545D01*
X938938Y-223711D01*
X940466Y-224003D01*
X941994Y-223420D01*
X943523Y-221670D01*
G01X954254Y-224003D02*
Y-212337D01*
G01Y-214670D02*
X955346Y-213503D01*
X956438Y-212628D01*
X957966Y-212337D01*
X959057Y-212628D01*
X960368Y-213503D01*
G01X874194Y-265503D02*
X875286Y-267253D01*
X876596Y-268420D01*
X878124Y-269003D01*
X879871Y-268420D01*
X881181Y-267253D01*
X882491Y-265503D01*
X882928Y-263170D01*
Y-251503D01*
G01X896061Y-269003D02*
X894314Y-268711D01*
X892786Y-267545D01*
X891476Y-265795D01*
X890602Y-263753D01*
X890166Y-261420D01*
Y-259086D01*
X890602Y-256753D01*
X891476Y-254711D01*
X892786Y-252962D01*
X894314Y-251795D01*
X896061Y-251503D01*
X897807Y-251795D01*
X899336Y-252962D01*
X900646Y-254711D01*
X901520Y-256753D01*
X901956Y-259086D01*
Y-261420D01*
X901520Y-263753D01*
X900646Y-265795D01*
X899336Y-267545D01*
X897807Y-268711D01*
X896061Y-269003D01*
G01X913561D02*
Y-261128D01*
X909194Y-251503D01*
G01X917928D02*
X913561Y-261128D01*
G01X1001011Y-269003D02*
Y-251503D01*
X998391Y-255003D01*
G01Y-269003D02*
X1003631D01*
G01X1014363Y-254420D02*
X1015673Y-252670D01*
X1017201Y-251795D01*
X1018948Y-251503D01*
X1021131Y-252086D01*
X1022659Y-253545D01*
X1023096Y-255294D01*
X1022878Y-257045D01*
X1022004Y-258503D01*
X1017638Y-261420D01*
X1015673Y-263461D01*
X1014363Y-266379D01*
X1013926Y-269003D01*
X1023096D01*
G01X1032081Y-269586D02*
X1039941Y-251503D01*
G01X1048708Y-265503D02*
X1050017Y-267545D01*
X1051764Y-268711D01*
X1053729Y-269003D01*
X1055476Y-268711D01*
X1057223Y-267253D01*
X1058314Y-265503D01*
X1058533Y-263753D01*
X1058096Y-261712D01*
X1056568Y-260253D01*
X1055039Y-259670D01*
X1053074D01*
G01X1055039D02*
X1056349Y-258795D01*
X1057441Y-257337D01*
X1057878Y-255587D01*
X1057441Y-253836D01*
X1056349Y-252378D01*
X1054384Y-251503D01*
X1052419Y-251795D01*
X1050454Y-252962D01*
G01X1071011Y-251503D02*
X1069264Y-252086D01*
X1067954Y-253545D01*
X1067081Y-255294D01*
X1066426Y-257628D01*
X1066208Y-260253D01*
X1066426Y-262878D01*
X1067081Y-265212D01*
X1067954Y-266962D01*
X1069264Y-268420D01*
X1071011Y-269003D01*
X1072757Y-268420D01*
X1074068Y-266962D01*
X1074941Y-265212D01*
X1075596Y-262878D01*
X1075814Y-260253D01*
X1075596Y-257628D01*
X1074941Y-255294D01*
X1074068Y-253545D01*
X1072757Y-252086D01*
X1071011Y-251503D01*
G01X1084581Y-269586D02*
X1092441Y-251503D01*
G01X1101863Y-254420D02*
X1103173Y-252670D01*
X1104701Y-251795D01*
X1106448Y-251503D01*
X1108631Y-252086D01*
X1110159Y-253545D01*
X1110596Y-255294D01*
X1110378Y-257045D01*
X1109504Y-258503D01*
X1105138Y-261420D01*
X1103173Y-263461D01*
X1101863Y-266379D01*
X1101426Y-269003D01*
X1110596D01*
G01X1123511Y-251503D02*
X1121764Y-252086D01*
X1120454Y-253545D01*
X1119581Y-255294D01*
X1118926Y-257628D01*
X1118708Y-260253D01*
X1118926Y-262878D01*
X1119581Y-265212D01*
X1120454Y-266962D01*
X1121764Y-268420D01*
X1123511Y-269003D01*
X1125257Y-268420D01*
X1126568Y-266962D01*
X1127441Y-265212D01*
X1128096Y-262878D01*
X1128314Y-260253D01*
X1128096Y-257628D01*
X1127441Y-255294D01*
X1126568Y-253545D01*
X1125257Y-252086D01*
X1123511Y-251503D01*
G01X1141011Y-269003D02*
Y-251503D01*
X1138391Y-255003D01*
G01Y-269003D02*
X1143631D01*
G01X1154363Y-261712D02*
X1155891Y-259670D01*
X1157201Y-258503D01*
X1158948Y-257920D01*
X1160476Y-258503D01*
X1161568Y-259670D01*
X1162441Y-261420D01*
X1162659Y-263461D01*
X1162441Y-265212D01*
X1161568Y-266962D01*
X1160257Y-268420D01*
X1158729Y-269003D01*
X1156983Y-268420D01*
X1155454Y-266670D01*
X1154581Y-264045D01*
X1154363Y-261128D01*
X1154799Y-257337D01*
X1155454Y-255294D01*
X1156546Y-253253D01*
X1158074Y-251795D01*
X1159603Y-251503D01*
X1161131Y-252086D01*
X1162223Y-253545D01*
G01X1048708Y-224003D02*
Y-206503D01*
X1053074D01*
X1054821Y-207378D01*
X1056131Y-208545D01*
X1057223Y-210294D01*
X1058096Y-212337D01*
X1058314Y-215253D01*
X1058096Y-218170D01*
X1057223Y-220212D01*
X1056131Y-221962D01*
X1054821Y-223128D01*
X1053074Y-224003D01*
X1048708D01*
G01X1074941D02*
Y-212337D01*
G01Y-214378D02*
X1074068Y-213212D01*
X1072757Y-212628D01*
X1071229Y-212337D01*
X1069701Y-212920D01*
X1068391Y-214086D01*
X1067517Y-215836D01*
X1067081Y-218170D01*
X1067517Y-220503D01*
X1068391Y-222253D01*
X1069701Y-223420D01*
X1071229Y-224003D01*
X1072757Y-223711D01*
X1074068Y-222837D01*
X1074941Y-221670D01*
G01X1088511Y-206503D02*
Y-224003D01*
G01X1085454Y-212337D02*
X1091568D01*
G01X1102736Y-216128D02*
X1109723D01*
X1109068Y-214086D01*
X1107976Y-212920D01*
X1106448Y-212337D01*
X1104919Y-212628D01*
X1103609Y-213503D01*
X1102736Y-215545D01*
X1102299Y-217295D01*
Y-219045D01*
X1102736Y-220795D01*
X1103828Y-222545D01*
X1105138Y-223711D01*
X1106666Y-224003D01*
X1108194Y-223420D01*
X1109723Y-221670D01*
M02*
